#ISCELL
  mstr_misc dns *
  *
#ISCELL
  pure_quanta quanta_title_block_c *
  *
#ISCELL
  pure_quanta_power universal_gnd *
  page182_i10
#CELL
  pure_quanta q_cap *
  page182_i100
#CELL
  pure_quanta q_res *
  page182_i101
#ISCELL
  pure_quanta_power universal_gnd *
  page182_i102
#CELL
  pure_quanta q_res *
  page182_i104
#CELL
  pure_quanta q_res *
  page182_i105
#ISCELL
  pure_quanta_power universal_gnd *
  page182_i107
#ISCELL
  pure_quanta_power universal_gnd *
  page182_i108
#ISCELL
  pure_quanta_power vcc_core *
  page182_i109
#CELL
  pure_quanta q_cap *
  page182_i118
#ISCELL
  pure_quanta_power universal_gnd *
  page182_i12
#ISCELL
  standard offpage *
  page182_i127
#CELL
  pure_quanta q_cap *
  page182_i13
#ISCELL
  pure_quanta_power vcc_core *
  page182_i14
#ISCELL
  pure_quanta_power universal_gnd *
  page182_i146
#CELL
  pure_quanta q_res *
  page182_i148
#ISCELL
  standard offpage *
  page182_i149
#ISCELL
  standard offpage *
  page182_i15
#ISCELL
  pure_quanta_power vcc_core *
  page182_i150
#CELL
  pure_quanta q_res *
  page182_i151
#CELL
  pure_quanta q_res *
  page182_i152
#CELL
  pure_quanta q_cap *
  page182_i153
#ISCELL
  pure_quanta_power universal_gnd *
  page182_i154
#ISCELL
  standard offpage *
  page182_i155
#ISCELL
  pure_quanta_power universal_gnd *
  page182_i159
#CELL
  pure_quanta q_cap *
  page182_i160
#ISCELL
  pure_quanta_power universal_gnd *
  page182_i161
#CELL
  pure_quanta q_cap *
  page182_i162
#CELL
  pure_quanta q_res *
  page182_i163
#ISCELL
  pure_quanta_power universal_gnd *
  page182_i165
#ISCELL
  pure_quanta_power universal_gnd *
  page182_i167
#CELL
  pure_quanta q_res *
  page182_i168
#CELL
  pure_quanta q_res *
  page182_i178
#CELL
  pure_quanta q_res *
  page182_i179
#ISCELL
  pure_quanta_power vcc_core *
  page182_i180
#ISCELL
  standard offpage *
  page182_i181
#ISCELL
  pure_quanta_power universal_gnd *
  page182_i188
#CELL
  pure_quanta q_res *
  page182_i189
#ISCELL
  pure_quanta_power vcc_core *
  page182_i190
#CELL
  pure_quanta q_res *
  page182_i211
#ISCELL
  pure_quanta_power universal_gnd *
  page182_i212
#ISCELL
  pure_quanta_power universal_gnd *
  page182_i213
#CELL
  pure_quanta q_res *
  page182_i214
#CELL
  pure_quanta q_res *
  page182_i215
#CELL
  pure_quanta q_res *
  page182_i216
#ISCELL
  pure_quanta_power universal_gnd *
  page182_i217
#ISCELL
  pure_quanta_power universal_gnd *
  page182_i218
#ISCELL
  pure_quanta_power universal_gnd *
  page182_i219
#ISCELL
  pure_quanta_power universal_gnd *
  page182_i220
#CELL
  pure_quanta q_res *
  page182_i221
#CELL
  pure_quanta q_res *
  page182_i222
#ISCELL
  standard offpage *
  page182_i223
#ISCELL
  standard offpage *
  page182_i224
#ISCELL
  standard offpage *
  page182_i225
#ISCELL
  standard offpage *
  page182_i226
#CELL
  pure_quanta q_res *
  page182_i227
#ISCELL
  pure_quanta_power universal_gnd *
  page182_i228
#ISCELL
  pure_quanta_power vcc_core *
  page182_i229
#CELL
  pure_quanta q_res *
  page182_i3
#CELL
  pure_quanta q_cap *
  page182_i36
#ISCELL
  pure_quanta_power universal_gnd *
  page182_i37
#CELL
  pure_quanta q_res *
  page182_i47
#CELL
  pure_quanta q_cap *
  page182_i49
#ISCELL
  pure_quanta_power universal_gnd *
  page182_i5
#ISCELL
  pure_quanta_power universal_gnd *
  page182_i50
#CELL
  pure_quanta q_res *
  page182_i66
#CELL
  pure_quanta q_res *
  page182_i67
#CELL
  pure_quanta q_res *
  page182_i68
#CELL
  pure_quanta raa229621gnpha0 *
  page182_i7
#ISCELL
  standard offpage *
  page182_i73
#ISCELL
  standard offpage *
  page182_i74
#ISCELL
  standard offpage *
  page182_i75
#CELL
  pure_quanta q_cap *
  page182_i76
#CELL
  pure_quanta q_res *
  page182_i77
#ISCELL
  standard offpage *
  page182_i79
#CELL
  pure_quanta q_cap *
  page182_i8
#ISCELL
  standard offpage *
  page182_i80
#CELL
  pure_quanta q_res *
  page182_i81
#CELL
  pure_quanta q_res *
  page182_i82
#ISCELL
  pure_quanta_power universal_gnd *
  page182_i83
#ISCELL
  pure_quanta_power vcc_core *
  page182_i84
#CELL
  pure_quanta q_res *
  page182_i94
#CELL
  pure_quanta q_res *
  page182_i95
#ISCELL
  pure_quanta_power vcc_core *
  page182_i96
#ISCELL
  standard offpage *
  page182_i97
#ISCELL
  pure_quanta_power universal_gnd *
  page182_i99
